# S9S_MB_2U (Grand Teton) — schematic netlist excerpt (pin names and nets, part order shuffled) for the footprints in the layout excerpt that follows; sources: Cadence DE-HDL packaged netlist, KiCad conversion of 03242023_DA0F0TMBIJ0_F0T_Motherboard_J_brd_V01_OCP.brd

C1332  Q_CAP  100NF 50V 10% X7R  pkg C0402  page 260 : A = P3V3_AUX ; B = GND
R3151  Q_RES  1K 1% EMPTY  pkg 0402LF  page 164 : A = P3V3_AUX ; B = PD_SMB_OCP2_HP_ADD1

(kicad_pcb
	(version 20260206)
	(generator "pcbnew")
	(generator_version "10.0")
	(general
		(thickness 1.6)
		(legacy_teardrops no)
	)
	(paper "A4")
	(title_block
		(title "03242023_DA0F0TMBIJ0_F0T_Motherboard_J_brd_V01_OCP.brd")
		(comment 1 "Grand Teton / footprints 3922-3923 of 6105")
	)
	(layers
		(0 "F.Cu" signal "TOP")
		(4 "In1.Cu" signal "GND")
		(6 "In2.Cu" signal "IN1")
		(8 "In3.Cu" signal "GND1")
		(10 "In4.Cu" signal "IN2")
		(12 "In5.Cu" signal "GND2")
		(14 "In6.Cu" signal "IN3")
		(16 "In7.Cu" signal "GND3")
		(18 "In8.Cu" signal "VCC")
		(20 "In9.Cu" signal "VCC1")
		(22 "In10.Cu" signal "GND4")
		(24 "In11.Cu" signal "IN4")
		(26 "In12.Cu" signal "GND5")
		(28 "In13.Cu" signal "IN5")
		(30 "In14.Cu" signal "GND6")
		(32 "In15.Cu" signal "IN6")
		(34 "In16.Cu" signal "GND7")
		(2 "B.Cu" signal "BOTTOM")
		(9 "F.Adhes" user "F.Adhesive")
		(11 "B.Adhes" user "B.Adhesive")
		(13 "F.Paste" user "Package Geometry/Pastemask Top")
		(15 "B.Paste" user "Package Geometry/Pastemask Bottom")
		(5 "F.SilkS" user "Ref Des/Silkscreen Top")
		(7 "B.SilkS" user "Ref Des/Silkscreen Bottom")
		(1 "F.Mask" user "Board Geometry/Soldermask Top")
		(3 "B.Mask" user "Board Geometry/Soldermask Bottom")
		(17 "Dwgs.User" user "User.Drawings")
		(19 "Cmts.User" user "User.Comments")
		(21 "Eco1.User" user "User.Eco1")
		(23 "Eco2.User" user "User.Eco2")
		(25 "Edge.Cuts" user "Board Geometry/Outline")
		(27 "Margin" user)
		(31 "F.CrtYd" user "Package Geometry/Place Bound Top")
		(29 "B.CrtYd" user "Package Geometry/Place Bound Bottom")
		(35 "F.Fab" user "Ref Des/Assembly Top")
		(33 "B.Fab" user "Ref Des/Assembly Bottom")
	)
	(footprint ""
		(layer "F.Cu")
		(at 445.090296 -51.305968 -90)
		(property "Reference" "C1332"
			(at 0 0 270)
			(layer "F.SilkS")
			(hide yes)
			(effects
				(font
					(size 1.27 1.27)
				)
			)
		)
		(property "Value" ""
			(at 0 0 270)
			(layer "F.Fab")
			(effects
				(font
					(size 1.27 1.27)
				)
			)
		)
		(duplicate_pad_numbers_are_jumpers no)
		(fp_line
			(start -0.7874 0.4064)
			(end -0.7874 -0.4064)
			(stroke
				(width 0.1524)
				(type default)
			)
			(layer "F.SilkS")
		)
		(fp_line
			(start 0.7874 0.4064)
			(end -0.7874 0.4064)
			(stroke
				(width 0.1524)
				(type default)
			)
			(layer "F.SilkS")
		)
		(fp_line
			(start -0.7874 -0.4064)
			(end 0.7874 -0.4064)
			(stroke
				(width 0.1524)
				(type default)
			)
			(layer "F.SilkS")
		)
		(fp_line
			(start 0.7874 -0.4064)
			(end 0.7874 0.4064)
			(stroke
				(width 0.1524)
				(type default)
			)
			(layer "F.SilkS")
		)
		(fp_line
			(start -0.67945 0.3048)
			(end -0.67945 -0.305054)
			(stroke
				(width 0.1)
				(type default)
			)
			(layer "F.Fab")
		)
		(fp_line
			(start -0.12065 0.3048)
			(end -0.67945 0.3048)
			(stroke
				(width 0.1)
				(type default)
			)
			(layer "F.Fab")
		)
		(fp_line
			(start 0.120396 0.3048)
			(end 0.120396 0.2794)
			(stroke
				(width 0.1)
				(type default)
			)
			(layer "F.Fab")
		)
		(fp_line
			(start 0.67945 0.3048)
			(end 0.120396 0.3048)
			(stroke
				(width 0.1)
				(type default)
			)
			(layer "F.Fab")
		)
		(fp_line
			(start -0.12065 0.2794)
			(end -0.12065 0.3048)
			(stroke
				(width 0.1)
				(type default)
			)
			(layer "F.Fab")
		)
		(fp_line
			(start 0.120396 0.2794)
			(end -0.12065 0.2794)
			(stroke
				(width 0.1)
				(type default)
			)
			(layer "F.Fab")
		)
		(fp_line
			(start -0.12065 -0.2794)
			(end 0.12065 -0.2794)
			(stroke
				(width 0.1)
				(type default)
			)
			(layer "F.Fab")
		)
		(fp_line
			(start 0.12065 -0.2794)
			(end 0.12065 -0.3048)
			(stroke
				(width 0.1)
				(type default)
			)
			(layer "F.Fab")
		)
		(fp_line
			(start 0.12065 -0.3048)
			(end 0.67945 -0.3048)
			(stroke
				(width 0.1)
				(type default)
			)
			(layer "F.Fab")
		)
		(fp_line
			(start 0.67945 -0.3048)
			(end 0.67945 0.3048)
			(stroke
				(width 0.1)
				(type default)
			)
			(layer "F.Fab")
		)
		(fp_line
			(start -0.67945 -0.305054)
			(end -0.12065 -0.305054)
			(stroke
				(width 0.1)
				(type default)
			)
			(layer "F.Fab")
		)
		(fp_line
			(start -0.12065 -0.305054)
			(end -0.12065 -0.2794)
			(stroke
				(width 0.1)
				(type default)
			)
			(layer "F.Fab")
		)
		(pad "1" smd circle
			(at -0.40005 0 270)
			(size 0 0)
			(layers "F.Cu" "F.Mask" "F.Paste")
			(net "P3V3_AUX")
		)
		(pad "2" smd circle
			(at 0.40005 0 270)
			(size 0 0)
			(layers "F.Cu" "F.Mask" "F.Paste")
			(net "GND")
		)
	)
	(footprint ""
		(layer "F.Cu")
		(at 134.2136 -125.758448)
		(property "Reference" "R3151"
			(at 0 0 0)
			(layer "F.SilkS")
			(hide yes)
			(effects
				(font
					(size 1.27 1.27)
				)
			)
		)
		(property "Value" ""
			(at 0 0 0)
			(layer "F.Fab")
			(effects
				(font
					(size 1.27 1.27)
				)
			)
		)
		(duplicate_pad_numbers_are_jumpers no)
		(fp_line
			(start -0.7874 -0.4064)
			(end 0.7874 -0.4064)
			(stroke
				(width 0.1524)
				(type default)
			)
			(layer "F.SilkS")
		)
		(fp_line
			(start -0.7874 0.4064)
			(end -0.7874 -0.4064)
			(stroke
				(width 0.1524)
				(type default)
			)
			(layer "F.SilkS")
		)
		(fp_line
			(start 0.7874 -0.4064)
			(end 0.7874 0.4064)
			(stroke
				(width 0.1524)
				(type default)
			)
			(layer "F.SilkS")
		)
		(fp_line
			(start 0.7874 0.4064)
			(end -0.7874 0.4064)
			(stroke
				(width 0.1524)
				(type default)
			)
			(layer "F.SilkS")
		)
		(fp_line
			(start -0.67945 -0.305054)
			(end -0.12065 -0.305054)
			(stroke
				(width 0.1)
				(type default)
			)
			(layer "F.Fab")
		)
		(fp_line
			(start -0.67945 0.3048)
			(end -0.67945 -0.305054)
			(stroke
				(width 0.1)
				(type default)
			)
			(layer "F.Fab")
		)
		(fp_line
			(start -0.12065 -0.305054)
			(end -0.12065 -0.2794)
			(stroke
				(width 0.1)
				(type default)
			)
			(layer "F.Fab")
		)
		(fp_line
			(start -0.12065 -0.2794)
			(end 0.12065 -0.2794)
			(stroke
				(width 0.1)
				(type default)
			)
			(layer "F.Fab")
		)
		(fp_line
			(start -0.12065 0.2794)
			(end -0.12065 0.3048)
			(stroke
				(width 0.1)
				(type default)
			)
			(layer "F.Fab")
		)
		(fp_line
			(start -0.12065 0.3048)
			(end -0.67945 0.3048)
			(stroke
				(width 0.1)
				(type default)
			)
			(layer "F.Fab")
		)
		(fp_line
			(start 0.120396 0.2794)
			(end -0.12065 0.2794)
			(stroke
				(width 0.1)
				(type default)
			)
			(layer "F.Fab")
		)
		(fp_line
			(start 0.120396 0.3048)
			(end 0.120396 0.2794)
			(stroke
				(width 0.1)
				(type default)
			)
			(layer "F.Fab")
		)
		(fp_line
			(start 0.12065 -0.3048)
			(end 0.67945 -0.3048)
			(stroke
				(width 0.1)
				(type default)
			)
			(layer "F.Fab")
		)
		(fp_line
			(start 0.12065 -0.2794)
			(end 0.12065 -0.3048)
			(stroke
				(width 0.1)
				(type default)
			)
			(layer "F.Fab")
		)
		(fp_line
			(start 0.67945 -0.3048)
			(end 0.67945 0.3048)
			(stroke
				(width 0.1)
				(type default)
			)
			(layer "F.Fab")
		)
		(fp_line
			(start 0.67945 0.3048)
			(end 0.120396 0.3048)
			(stroke
				(width 0.1)
				(type default)
			)
			(layer "F.Fab")
		)
		(pad "1" smd circle
			(at -0.40005 0)
			(size 0 0)
			(layers "F.Cu" "F.Mask" "F.Paste")
			(net "P3V3_AUX")
		)
		(pad "2" smd circle
			(at 0.40005 0)
			(size 0 0)
			(layers "F.Cu" "F.Mask" "F.Paste")
			(net "PD_SMB_OCP2_HP_ADD1")
		)
	)
)
